(kicad_pcb
	(version 20241229)
	(generator "pcbnew")
	(generator_version "9.0")
	(general
		(thickness 1.711)
		(legacy_teardrops no)
	)
	(paper "A4")
	(title_block
		(title "Antmicro Baseboard for Jetson AGX Thor")
		(date "2026-02-18")
		(rev "1.1.0")
		(company "Antmicro Ltd")
		(comment 1 "www.antmicro.com")
		(comment 9 "footprints 933-937 of 1170")
	)
	(layers
		(0 "F.Cu" signal)
		(4 "In1.Cu" signal)
		(6 "In2.Cu" signal)
		(8 "In3.Cu" signal)
		(10 "In4.Cu" jumper)
		(12 "In5.Cu" signal)
		(14 "In6.Cu" signal)
		(16 "In7.Cu" signal)
		(18 "In8.Cu" signal)
		(2 "B.Cu" signal)
		(9 "F.Adhes" user "F.Adhesive")
		(11 "B.Adhes" user "B.Adhesive")
		(13 "F.Paste" user)
		(15 "B.Paste" user)
		(5 "F.SilkS" user "F.Silkscreen")
		(7 "B.SilkS" user "B.Silkscreen")
		(1 "F.Mask" user)
		(3 "B.Mask" user)
		(17 "Dwgs.User" user "User.Drawings")
		(19 "Cmts.User" user "User.Comments")
		(21 "Eco1.User" user "User.Eco1")
		(23 "Eco2.User" user "User.Eco2")
		(25 "Edge.Cuts" user)
		(27 "Margin" user)
		(31 "F.CrtYd" user "F.Courtyard")
		(29 "B.CrtYd" user "B.Courtyard")
		(35 "F.Fab" user)
		(33 "B.Fab" user)
	)
	(footprint "antmicro-footprints:SOT-523"
		(layer "B.Cu")
		(at 95.88 65.5 -90)
		(property "Reference" "Q8"
			(at 1.1 0.28 90)
			(layer "B.SilkS")
			(effects
				(font
					(size 0.7 0.7)
					(thickness 0.15)
				)
				(justify left bottom mirror)
			)
		)
		(property "Value" "DMG1012T-7"
			(at 0.1 -1.824 90)
			(layer "B.Fab")
			(effects
				(font
					(size 0.7 0.7)
					(thickness 0.15)
				)
				(justify left bottom mirror)
			)
		)
		(property "Datasheet" "https://www.diodes.com/assets/Datasheets/ds31783.pdf"
			(at 0 0 90)
			(layer "B.Fab")
			(hide yes)
			(effects
				(font
					(size 1.27 1.27)
					(thickness 0.15)
				)
				(justify mirror)
			)
		)
		(property "Description" "Power MOSFET, N Channel, 20 V, 630 mA, 0.3 ohm, SOT-523, Surface Mount"
			(at 0 0 90)
			(layer "B.Fab")
			(hide yes)
			(effects
				(font
					(size 1.27 1.27)
					(thickness 0.15)
				)
				(justify mirror)
			)
		)
		(property "MPN" "DMG1012T-7"
			(at 0 0 270)
			(unlocked yes)
			(layer "B.Fab")
			(hide yes)
			(effects
				(font
					(size 1 1)
					(thickness 0.15)
				)
				(justify mirror)
			)
		)
		(property "Manufacturer" "Diodes Incorporated"
			(at 0 0 270)
			(unlocked yes)
			(layer "B.Fab")
			(hide yes)
			(effects
				(font
					(size 1 1)
					(thickness 0.15)
				)
				(justify mirror)
			)
		)
		(property "Author" "Antmicro"
			(at 0 0 270)
			(unlocked yes)
			(layer "B.Fab")
			(hide yes)
			(effects
				(font
					(size 1 1)
					(thickness 0.15)
				)
				(justify mirror)
			)
		)
		(property "License" "Apache-2.0"
			(at 0 0 270)
			(unlocked yes)
			(layer "B.Fab")
			(hide yes)
			(effects
				(font
					(size 1 1)
					(thickness 0.15)
				)
				(justify mirror)
			)
		)
		(sheetname "/SoM_Power/")
		(sheetfile "som_power.kicad_sch")
		(attr smd)
		(fp_line
			(start -0.725 0.551)
			(end -0.277 0.551)
			(stroke
				(width 0.15)
				(type solid)
			)
			(layer "B.SilkS")
		)
		(fp_line
			(start -0.277 0.551)
			(end -0.277 0.75)
			(stroke
				(width 0.15)
				(type solid)
			)
			(layer "B.SilkS")
		)
		(fp_line
			(start -0.927 0.351)
			(end -0.725 0.551)
			(stroke
				(width 0.15)
				(type solid)
			)
			(layer "B.SilkS")
		)
		(fp_line
			(start -0.927 0.051)
			(end -0.927 0.351)
			(stroke
				(width 0.15)
				(type solid)
			)
			(layer "B.SilkS")
		)
		(fp_circle
			(center -0.9652 -0.9652)
			(end -0.9152 -0.9652)
			(stroke
				(width 0.15)
				(type solid)
			)
			(fill yes)
			(layer "B.SilkS")
		)
		(fp_line
			(start -1.12 1.16)
			(end 1.1 1.16)
			(stroke
				(width 0.05)
				(type solid)
			)
			(layer "B.CrtYd")
		)
		(fp_line
			(start -1.12 1.16)
			(end -1.12 -1.15)
			(stroke
				(width 0.05)
				(type solid)
			)
			(layer "B.CrtYd")
		)
		(fp_line
			(start 1.1 1.16)
			(end 1.1 -1.15)
			(stroke
				(width 0.05)
				(type solid)
			)
			(layer "B.CrtYd")
		)
		(fp_line
			(start -1.12 -1.15)
			(end 1.1 -1.15)
			(stroke
				(width 0.05)
				(type solid)
			)
			(layer "B.CrtYd")
		)
		(fp_line
			(start -0.652 0.425)
			(end -0.802 0.276)
			(stroke
				(width 0.15)
				(type solid)
			)
			(layer "B.Fab")
		)
		(fp_line
			(start 0.8 0.425)
			(end -0.652 0.425)
			(stroke
				(width 0.15)
				(type solid)
			)
			(layer "B.Fab")
		)
		(fp_line
			(start 0.8 0.425)
			(end 0.8 -0.424)
			(stroke
				(width 0.15)
				(type solid)
			)
			(layer "B.Fab")
		)
		(fp_line
			(start -0.802 0.276)
			(end -0.802 -0.424)
			(stroke
				(width 0.15)
				(type solid)
			)
			(layer "B.Fab")
		)
		(fp_line
			(start 0.8 -0.424)
			(end -0.802 -0.424)
			(stroke
				(width 0.15)
				(type solid)
			)
			(layer "B.Fab")
		)
		(fp_circle
			(center -0.9652 -0.9652)
			(end -0.9144 -0.9652)
			(stroke
				(width 0.15)
				(type solid)
			)
			(fill no)
			(layer "B.Fab")
		)
		(fp_text user "${REFERENCE}"
			(at -1.12 -3.824 90)
			(layer "B.Fab")
			(effects
				(font
					(size 0.7 0.7)
					(thickness 0.15)
				)
				(justify left bottom mirror)
			)
		)
		(fp_text user "Author: Antmicro"
			(at -1.12 -6.224 90)
			(layer "B.Fab")
			(effects
				(font
					(size 0.7 0.7)
					(thickness 0.15)
				)
				(justify left bottom mirror)
			)
		)
		(fp_text user "License: Apache-2.0"
			(at -1.12 -5.024 90)
			(layer "B.Fab")
			(effects
				(font
					(size 0.7 0.7)
					(thickness 0.15)
				)
				(justify left bottom mirror)
			)
		)
		(pad "1" smd rect
			(at -0.5 -0.65 270)
			(size 0.4 0.51)
			(layers "B.Cu" "B.Mask" "B.Paste")
			(net 1298 "Net-(Q37-G)")
			(pinfunction "G")
			(pintype "input")
		)
		(pad "2" smd rect
			(at 0.498 -0.65 270)
			(size 0.4 0.51)
			(layers "B.Cu" "B.Mask" "B.Paste")
			(net 1 "GND")
			(pinfunction "S")
			(pintype "passive")
		)
		(pad "3" smd rect
			(at 0 0.652 270)
			(size 0.4 0.51)
			(layers "B.Cu" "B.Mask" "B.Paste")
			(net 884 "Net-(Q8-D)")
			(pinfunction "D")
			(pintype "passive")
		)
	)
	(footprint "antmicro-footprints:R_0402_1005Metric"
		(layer "B.Cu")
		(at 141.3 61.1 -90)
		(descr "Resistor SMD 0402")
		(tags "resistor SMD 0402")
		(property "Reference" "R246"
			(at 0.9 -0.4 90)
			(layer "B.SilkS")
			(effects
				(font
					(size 0.7 0.7)
					(thickness 0.15)
				)
				(justify left bottom mirror)
			)
		)
		(property "Value" "R_200R_0402"
			(at -1.011843 -1.772047 90)
			(layer "B.Fab")
			(effects
				(font
					(size 0.7 0.7)
					(thickness 0.15)
				)
				(justify left bottom mirror)
			)
		)
		(property "Datasheet" "https://www.bourns.com/docs/product-datasheets/cr.pdf"
			(at 0 0 90)
			(layer "B.Fab")
			(hide yes)
			(effects
				(font
					(size 1.27 1.27)
					(thickness 0.15)
				)
				(justify mirror)
			)
		)
		(property "Description" "SMD Chip Resistor, 200 ohm, ± 1%, 62.5 mW, 0402 [1005 Metric], Thick Film, General Purpose"
			(at 0 0 90)
			(layer "B.Fab")
			(hide yes)
			(effects
				(font
					(size 1.27 1.27)
					(thickness 0.15)
				)
				(justify mirror)
			)
		)
		(property "Manufacturer" "Bourns"
			(at 0 0 90)
			(unlocked yes)
			(layer "B.Fab")
			(hide yes)
			(effects
				(font
					(size 1 1)
					(thickness 0.15)
				)
				(justify mirror)
			)
		)
		(property "MPN" "CR0402-FX-2000GLF"
			(at 0 0 90)
			(unlocked yes)
			(layer "B.Fab")
			(hide yes)
			(effects
				(font
					(size 1 1)
					(thickness 0.15)
				)
				(justify mirror)
			)
		)
		(property "Val" "200R"
			(at 0 0 90)
			(unlocked yes)
			(layer "B.Fab")
			(hide yes)
			(effects
				(font
					(size 1 1)
					(thickness 0.15)
				)
				(justify mirror)
			)
		)
		(property "License" "Apache-2.0"
			(at 0 0 90)
			(unlocked yes)
			(layer "B.Fab")
			(hide yes)
			(effects
				(font
					(size 1 1)
					(thickness 0.15)
				)
				(justify mirror)
			)
		)
		(property "Author" "Antmicro"
			(at 0 0 90)
			(unlocked yes)
			(layer "B.Fab")
			(hide yes)
			(effects
				(font
					(size 1 1)
					(thickness 0.15)
				)
				(justify mirror)
			)
		)
		(property "Tolerance" "1%"
			(at 0 0 90)
			(unlocked yes)
			(layer "B.Fab")
			(hide yes)
			(effects
				(font
					(size 1 1)
					(thickness 0.15)
				)
				(justify mirror)
			)
		)
		(sheetname "/Peripherals/")
		(sheetfile "peripherals.kicad_sch")
		(attr smd)
		(fp_rect
			(start -0.925 0.47)
			(end 0.925 -0.47)
			(stroke
				(width 0.05)
				(type default)
			)
			(fill no)
			(layer "B.CrtYd")
		)
		(fp_rect
			(start -0.5 0.25)
			(end 0.5 -0.25)
			(stroke
				(width 0.15)
				(type solid)
			)
			(fill no)
			(layer "B.Fab")
		)
		(fp_text user "Author: Antmicro"
			(at -0.95 -4.169 90)
			(layer "B.Fab")
			(effects
				(font
					(size 0.7 0.7)
					(thickness 0.15)
				)
				(justify left bottom mirror)
			)
		)
		(fp_text user "${REFERENCE}"
			(at -0.95 -3.168 90)
			(layer "B.Fab")
			(effects
				(font
					(size 0.7 0.7)
					(thickness 0.15)
				)
				(justify left bottom mirror)
			)
		)
		(fp_text user "License: Apache-2.0"
			(at -0.95 -5.169 90)
			(layer "B.Fab")
			(effects
				(font
					(size 0.7 0.7)
					(thickness 0.15)
				)
				(justify left bottom mirror)
			)
		)
		(pad "1" smd roundrect
			(at -0.48 0 270)
			(size 0.59 0.64)
			(layers "B.Cu" "B.Mask" "B.Paste")
			(roundrect_rratio 0.25)
			(net 548 "Net-(D44-A)")
			(pintype "passive")
		)
		(pad "2" smd roundrect
			(at 0.48 0 270)
			(size 0.59 0.64)
			(layers "B.Cu" "B.Mask" "B.Paste")
			(roundrect_rratio 0.25)
			(net 839 "/Peripherals/I2C_CONN2_3V3")
			(pintype "passive")
		)
	)
	(footprint "antmicro-footprints:R_0402_1005Metric"
		(layer "B.Cu")
		(at 184.25 57.5 -90)
		(descr "Resistor SMD 0402")
		(tags "resistor SMD 0402")
		(property "Reference" "R27"
			(at -3.58 -0.58 90)
			(layer "B.SilkS")
			(effects
				(font
					(size 0.7 0.7)
					(thickness 0.15)
				)
				(justify left bottom mirror)
			)
		)
		(property "Value" "R_2k2_0402"
			(at -1.011843 -1.772047 90)
			(layer "B.Fab")
			(effects
				(font
					(size 0.7 0.7)
					(thickness 0.15)
				)
				(justify left bottom mirror)
			)
		)
		(property "Datasheet" "https://www.bourns.com/docs/product-datasheets/cr.pdf"
			(at 0 0 90)
			(layer "B.Fab")
			(hide yes)
			(effects
				(font
					(size 1.27 1.27)
					(thickness 0.15)
				)
				(justify mirror)
			)
		)
		(property "Description" "SMD Chip Resistor, 2.2 kohm, ± 1%, 62.5 mW, 0402 [1005 Metric], Thick Film, General Purpose"
			(at 0 0 90)
			(layer "B.Fab")
			(hide yes)
			(effects
				(font
					(size 1.27 1.27)
					(thickness 0.15)
				)
				(justify mirror)
			)
		)
		(property "Manufacturer" "Bourns"
			(at 0 0 90)
			(unlocked yes)
			(layer "B.Fab")
			(hide yes)
			(effects
				(font
					(size 1 1)
					(thickness 0.15)
				)
				(justify mirror)
			)
		)
		(property "MPN" "CR0402-FX-2201GLF"
			(at 0 0 90)
			(unlocked yes)
			(layer "B.Fab")
			(hide yes)
			(effects
				(font
					(size 1 1)
					(thickness 0.15)
				)
				(justify mirror)
			)
		)
		(property "Val" "2k2"
			(at 0 0 90)
			(unlocked yes)
			(layer "B.Fab")
			(hide yes)
			(effects
				(font
					(size 1 1)
					(thickness 0.15)
				)
				(justify mirror)
			)
		)
		(property "License" "Apache-2.0"
			(at 0 0 90)
			(unlocked yes)
			(layer "B.Fab")
			(hide yes)
			(effects
				(font
					(size 1 1)
					(thickness 0.15)
				)
				(justify mirror)
			)
		)
		(property "Author" "Antmicro"
			(at 0 0 90)
			(unlocked yes)
			(layer "B.Fab")
			(hide yes)
			(effects
				(font
					(size 1 1)
					(thickness 0.15)
				)
				(justify mirror)
			)
		)
		(property "Tolerance" "1%"
			(at 0 0 90)
			(unlocked yes)
			(layer "B.Fab")
			(hide yes)
			(effects
				(font
					(size 1 1)
					(thickness 0.15)
				)
				(justify mirror)
			)
		)
		(sheetname "/Power/")
		(sheetfile "power.kicad_sch")
		(attr smd)
		(fp_rect
			(start -0.925 0.47)
			(end 0.925 -0.47)
			(stroke
				(width 0.05)
				(type default)
			)
			(fill no)
			(layer "B.CrtYd")
		)
		(fp_rect
			(start -0.5 0.25)
			(end 0.5 -0.25)
			(stroke
				(width 0.15)
				(type solid)
			)
			(fill no)
			(layer "B.Fab")
		)
		(fp_text user "Author: Antmicro"
			(at -0.95 -4.169 90)
			(layer "B.Fab")
			(effects
				(font
					(size 0.7 0.7)
					(thickness 0.15)
				)
				(justify left bottom mirror)
			)
		)
		(fp_text user "${REFERENCE}"
			(at -0.95 -3.168 90)
			(layer "B.Fab")
			(effects
				(font
					(size 0.7 0.7)
					(thickness 0.15)
				)
				(justify left bottom mirror)
			)
		)
		(fp_text user "License: Apache-2.0"
			(at -0.95 -5.169 90)
			(layer "B.Fab")
			(effects
				(font
					(size 0.7 0.7)
					(thickness 0.15)
				)
				(justify left bottom mirror)
			)
		)
		(pad "1" smd roundrect
			(at -0.48 0 270)
			(size 0.59 0.64)
			(layers "B.Cu" "B.Mask" "B.Paste")
			(roundrect_rratio 0.25)
			(net 528 "Net-(D4-A)")
			(pintype "passive")
		)
		(pad "2" smd roundrect
			(at 0.48 0 270)
			(size 0.59 0.64)
			(layers "B.Cu" "B.Mask" "B.Paste")
			(roundrect_rratio 0.25)
			(net 13 "VCC")
			(pintype "passive")
		)
	)
	(footprint "antmicro-footprints:R_0402_1005Metric"
		(layer "B.Cu")
		(at 208.726 145.01 180)
		(descr "Resistor SMD 0402")
		(tags "resistor SMD 0402")
		(property "Reference" "R186"
			(at -3.83 -0.530001 0)
			(layer "B.SilkS")
			(effects
				(font
					(size 0.7 0.7)
					(thickness 0.15)
				)
				(justify left bottom mirror)
			)
		)
		(property "Value" "R_0R_0402"
			(at -1.011843 -1.772046 0)
			(layer "B.Fab")
			(effects
				(font
					(size 0.7 0.7)
					(thickness 0.15)
				)
				(justify left bottom mirror)
			)
		)
		(property "Datasheet" "https://industrial.panasonic.com/cdbs/www-data/pdf/RDA0000/AOA0000C301.pdf"
			(at 0 0 0)
			(layer "B.Fab")
			(hide yes)
			(effects
				(font
					(size 1.27 1.27)
					(thickness 0.15)
				)
				(justify mirror)
			)
		)
		(property "Description" "SMD Chip Resistor, Jumper, 0 ohm, 100 mW, 0402 [1005 Metric], Thick Film, General Purpose"
			(at 0 0 0)
			(layer "B.Fab")
			(hide yes)
			(effects
				(font
					(size 1.27 1.27)
					(thickness 0.15)
				)
				(justify mirror)
			)
		)
		(property "MPN" "ERJ2GE0R00X"
			(at 0 0 0)
			(unlocked yes)
			(layer "B.Fab")
			(hide yes)
			(effects
				(font
					(size 1 1)
					(thickness 0.15)
				)
				(justify mirror)
			)
		)
		(property "Manufacturer" "Panasonic"
			(at 0 0 0)
			(unlocked yes)
			(layer "B.Fab")
			(hide yes)
			(effects
				(font
					(size 1 1)
					(thickness 0.15)
				)
				(justify mirror)
			)
		)
		(property "License" "Apache-2.0"
			(at 0 0 0)
			(unlocked yes)
			(layer "B.Fab")
			(hide yes)
			(effects
				(font
					(size 1 1)
					(thickness 0.15)
				)
				(justify mirror)
			)
		)
		(property "Author" "Antmicro"
			(at 0 0 0)
			(unlocked yes)
			(layer "B.Fab")
			(hide yes)
			(effects
				(font
					(size 1 1)
					(thickness 0.15)
				)
				(justify mirror)
			)
		)
		(property "Val" "0R"
			(at 0 0 0)
			(unlocked yes)
			(layer "B.Fab")
			(hide yes)
			(effects
				(font
					(size 1 1)
					(thickness 0.15)
				)
				(justify mirror)
			)
		)
		(property "Tolerance" "~"
			(at 0 0 0)
			(unlocked yes)
			(layer "B.Fab")
			(hide yes)
			(effects
				(font
					(size 1 1)
					(thickness 0.15)
				)
				(justify mirror)
			)
		)
		(property "Current" "1A"
			(at 0 0 0)
			(unlocked yes)
			(layer "B.Fab")
			(hide yes)
			(effects
				(font
					(size 1 1)
					(thickness 0.15)
				)
				(justify mirror)
			)
		)
		(sheetname "/SFP/")
		(sheetfile "sfp.kicad_sch")
		(attr smd)
		(fp_poly
			(pts
				(xy -0.925 0.47) (xy 0.925 0.47) (xy 0.925 -0.47) (xy -0.925 -0.47)
			)
			(stroke
				(width 0.05)
				(type default)
			)
			(fill no)
			(layer "B.CrtYd")
		)
		(fp_poly
			(pts
				(xy -0.5 0.25) (xy 0.5 0.25) (xy 0.5 -0.25) (xy -0.5 -0.25)
			)
			(stroke
				(width 0.15)
				(type solid)
			)
			(fill no)
			(layer "B.Fab")
		)
		(fp_text user "${REFERENCE}"
			(at -0.95 -3.168 0)
			(layer "B.Fab")
			(effects
				(font
					(size 0.7 0.7)
					(thickness 0.15)
				)
				(justify left bottom mirror)
			)
		)
		(fp_text user "Author: Antmicro"
			(at -0.95 -4.169 0)
			(layer "B.Fab")
			(effects
				(font
					(size 0.7 0.7)
					(thickness 0.15)
				)
				(justify left bottom mirror)
			)
		)
		(fp_text user "License: Apache-2.0"
			(at -0.949999 -5.169 0)
			(layer "B.Fab")
			(effects
				(font
					(size 0.7 0.7)
					(thickness 0.15)
				)
				(justify left bottom mirror)
			)
		)
		(pad "1" smd roundrect
			(at -0.48 0 180)
			(size 0.59 0.64)
			(layers "B.Cu" "B.Mask" "B.Paste")
			(roundrect_rratio 0.25)
			(net 1000 "/SFP/I2C_{SFP}.SCL")
			(pintype "passive")
		)
		(pad "2" smd roundrect
			(at 0.48 0 180)
			(size 0.59 0.64)
			(layers "B.Cu" "B.Mask" "B.Paste")
			(roundrect_rratio 0.25)
			(net 823 "/SFP/SCL_SFP")
			(pintype "passive")
		)
	)
	(footprint "antmicro-footprints:R_0402_1005Metric"
		(layer "B.Cu")
		(at 216 88.2 180)
		(descr "Resistor SMD 0402")
		(tags "resistor SMD 0402")
		(property "Reference" "R138"
			(at -7.6 -2.4 0)
			(layer "B.SilkS")
			(effects
				(font
					(size 0.7 0.7)
					(thickness 0.15)
				)
				(justify left bottom mirror)
			)
		)
		(property "Value" "R_1k_0402"
			(at -1.011843 -1.772047 0)
			(layer "B.Fab")
			(effects
				(font
					(size 0.7 0.7)
					(thickness 0.15)
				)
				(justify left bottom mirror)
			)
		)
		(property "Datasheet" "https://www.bourns.com/docs/product-datasheets/cr.pdf"
			(at 0 0 0)
			(layer "B.Fab")
			(hide yes)
			(effects
				(font
					(size 1.27 1.27)
					(thickness 0.15)
				)
				(justify mirror)
			)
		)
		(property "Description" "SMD Chip Resistor, 1 kohm, ± 1%, 63 mW, 0402 [1005 Metric], Thick Film, General Purpose"
			(at 0 0 0)
			(layer "B.Fab")
			(hide yes)
			(effects
				(font
					(size 1.27 1.27)
					(thickness 0.15)
				)
				(justify mirror)
			)
		)
		(property "Manufacturer" "Bourns"
			(at 0 0 0)
			(unlocked yes)
			(layer "B.Fab")
			(hide yes)
			(effects
				(font
					(size 1 1)
					(thickness 0.15)
				)
				(justify mirror)
			)
		)
		(property "MPN" "CR0402-FX-1001GLF"
			(at 0 0 0)
			(unlocked yes)
			(layer "B.Fab")
			(hide yes)
			(effects
				(font
					(size 1 1)
					(thickness 0.15)
				)
				(justify mirror)
			)
		)
		(property "Val" "1k"
			(at 0 0 0)
			(unlocked yes)
			(layer "B.Fab")
			(hide yes)
			(effects
				(font
					(size 1 1)
					(thickness 0.15)
				)
				(justify mirror)
			)
		)
		(property "License" "Apache-2.0"
			(at 0 0 0)
			(unlocked yes)
			(layer "B.Fab")
			(hide yes)
			(effects
				(font
					(size 1 1)
					(thickness 0.15)
				)
				(justify mirror)
			)
		)
		(property "Author" "Antmicro"
			(at 0 0 0)
			(unlocked yes)
			(layer "B.Fab")
			(hide yes)
			(effects
				(font
					(size 1 1)
					(thickness 0.15)
				)
				(justify mirror)
			)
		)
		(property "Tolerance" "1%"
			(at 0 0 0)
			(unlocked yes)
			(layer "B.Fab")
			(hide yes)
			(effects
				(font
					(size 1 1)
					(thickness 0.15)
				)
				(justify mirror)
			)
		)
		(sheetname "/USB DP Alt mode/")
		(sheetfile "usb_dp.kicad_sch")
		(attr smd exclude_from_pos_files exclude_from_bom dnp)
		(fp_rect
			(start -0.925 0.47)
			(end 0.925 -0.47)
			(stroke
				(width 0.05)
				(type default)
			)
			(fill no)
			(layer "B.CrtYd")
		)
		(fp_rect
			(start -0.5 0.25)
			(end 0.5 -0.25)
			(stroke
				(width 0.15)
				(type solid)
			)
			(fill no)
			(layer "B.Fab")
		)
		(fp_text user "License: Apache-2.0"
			(at -0.95 -5.169 0)
			(layer "B.Fab")
			(effects
				(font
					(size 0.7 0.7)
					(thickness 0.15)
				)
				(justify left bottom mirror)
			)
		)
		(fp_text user "Author: Antmicro"
			(at -0.95 -4.169 0)
			(layer "B.Fab")
			(effects
				(font
					(size 0.7 0.7)
					(thickness 0.15)
				)
				(justify left bottom mirror)
			)
		)
		(fp_text user "${REFERENCE}"
			(at -0.95 -3.168 0)
			(layer "B.Fab")
			(effects
				(font
					(size 0.7 0.7)
					(thickness 0.15)
				)
				(justify left bottom mirror)
			)
		)
		(pad "1" smd roundrect
			(at -0.48 0 180)
			(size 0.59 0.64)
			(layers "B.Cu" "B.Mask" "B.Paste")
			(roundrect_rratio 0.25)
			(net 968 "/USB DP Alt mode/USBC1_EQ0")
			(pintype "passive")
		)
		(pad "2" smd roundrect
			(at 0.48 0 180)
			(size 0.59 0.64)
			(layers "B.Cu" "B.Mask" "B.Paste")
			(roundrect_rratio 0.25)
			(net 2 "+3V3")
			(pintype "passive")
		)
	)
)
